(kicad_pcb
	(version 20260206)
	(generator "pcbnew")
	(generator_version "10.0")
	(general
		(thickness 1.6)
		(legacy_teardrops no)
	)
	(paper "A4")
	(title_block
		(title "04192023_DAF0TMB3IC0_F0TG_MB_C_brd_V02_OCP.brd")
		(comment 1 "Grand Teton / footprints 1311-1316 of 8354")
	)
	(layers
		(0 "F.Cu" signal "TOP")
		(4 "In1.Cu" signal "GND")
		(6 "In2.Cu" signal "IN1")
		(8 "In3.Cu" signal "GND1")
		(10 "In4.Cu" signal "IN2")
		(12 "In5.Cu" signal "GND2")
		(14 "In6.Cu" signal "IN3")
		(16 "In7.Cu" signal "GND3")
		(18 "In8.Cu" signal "VCC")
		(20 "In9.Cu" signal "VCC1")
		(22 "In10.Cu" signal "GND4")
		(24 "In11.Cu" signal "IN4")
		(26 "In12.Cu" signal "GND5")
		(28 "In13.Cu" signal "IN5")
		(30 "In14.Cu" signal "GND6")
		(32 "In15.Cu" signal "IN6")
		(34 "In16.Cu" signal "GND7")
		(2 "B.Cu" signal "BOTTOM")
		(9 "F.Adhes" user "F.Adhesive")
		(11 "B.Adhes" user "B.Adhesive")
		(13 "F.Paste" user "Package Geometry/Pastemask Top")
		(15 "B.Paste" user "Package Geometry/Pastemask Bottom")
		(5 "F.SilkS" user "Ref Des/Silkscreen Top")
		(7 "B.SilkS" user "Ref Des/Silkscreen Bottom")
		(1 "F.Mask" user "Board Geometry/Soldermask Top")
		(3 "B.Mask" user "Board Geometry/Soldermask Bottom")
		(17 "Dwgs.User" user "User.Drawings")
		(19 "Cmts.User" user "User.Comments")
		(21 "Eco1.User" user "User.Eco1")
		(23 "Eco2.User" user "User.Eco2")
		(25 "Edge.Cuts" user "Board Geometry/Outline")
		(27 "Margin" user)
		(31 "F.CrtYd" user "Package Geometry/Place Bound Top")
		(29 "B.CrtYd" user "Package Geometry/Place Bound Bottom")
		(35 "F.Fab" user "Ref Des/Assembly Top")
		(33 "B.Fab" user "Ref Des/Assembly Bottom")
	)
	(footprint ""
		(layer "F.Cu")
		(at 364.313978 -177.771298 180)
		(property "Reference" "PU6"
			(at -0.973074 -6.571742 0)
			(unlocked yes)
			(layer "F.SilkS")
			(effects
				(font
					(size 0.7874 0.5842)
					(thickness 0.1524)
				)
				(justify left)
			)
		)
		(property "Value" ""
			(at 0 0 180)
			(layer "F.Fab")
			(effects
				(font
					(size 1.27 1.27)
				)
			)
		)
		(duplicate_pad_numbers_are_jumpers no)
		(fp_line
			(start 2.500122 2.999994)
			(end 2.2987 2.999994)
			(stroke
				(width 0.1524)
				(type default)
			)
			(layer "F.SilkS")
		)
		(fp_line
			(start 2.500122 2.339594)
			(end 2.500122 2.999994)
			(stroke
				(width 0.1524)
				(type default)
			)
			(layer "F.SilkS")
		)
		(fp_line
			(start 2.500122 -2.999994)
			(end 2.500122 -2.44348)
			(stroke
				(width 0.1524)
				(type default)
			)
			(layer "F.SilkS")
		)
		(fp_line
			(start 2.31394 -2.999994)
			(end 2.500122 -2.999994)
			(stroke
				(width 0.1524)
				(type default)
			)
			(layer "F.SilkS")
		)
		(fp_line
			(start -2.2987 2.999994)
			(end -2.500122 2.999994)
			(stroke
				(width 0.1524)
				(type default)
			)
			(layer "F.SilkS")
		)
		(fp_line
			(start -2.500122 2.999994)
			(end -2.500122 2.339594)
			(stroke
				(width 0.1524)
				(type default)
			)
			(layer "F.SilkS")
		)
		(fp_line
			(start -2.500122 0.6604)
			(end -2.500122 0.229108)
			(stroke
				(width 0.1524)
				(type default)
			)
			(layer "F.SilkS")
		)
		(fp_line
			(start -2.500122 -2.529078)
			(end -2.500122 -2.999994)
			(stroke
				(width 0.1524)
				(type default)
			)
			(layer "F.SilkS")
		)
		(fp_line
			(start -2.500122 -2.999994)
			(end -2.24409 -2.999994)
			(stroke
				(width 0.1524)
				(type default)
			)
			(layer "F.SilkS")
		)
		(fp_poly
			(pts
				(xy -2.686558 -2.45618) (xy -3.376422 -2.68605) (xy -2.916428 -3.146044)
			)
			(stroke
				(width 0)
				(type default)
			)
			(fill yes)
			(layer "F.SilkS")
		)
		(fp_line
			(start 2.500122 2.999994)
			(end -2.500122 2.999994)
			(stroke
				(width 0.1)
				(type default)
			)
			(layer "F.Fab")
		)
		(fp_line
			(start 2.500122 -2.999994)
			(end 2.500122 2.999994)
			(stroke
				(width 0.1)
				(type default)
			)
			(layer "F.Fab")
		)
		(fp_line
			(start -2.500122 2.999994)
			(end -2.500122 -2.999994)
			(stroke
				(width 0.1)
				(type default)
			)
			(layer "F.Fab")
		)
		(fp_line
			(start -2.500122 -2.999994)
			(end 2.500122 -2.999994)
			(stroke
				(width 0.1)
				(type default)
			)
			(layer "F.Fab")
		)
		(fp_poly
			(pts
				(xy -4.218432 -2.783078) (xy -4.218432 -1.767078) (xy -3.202432 -2.275078)
			)
			(stroke
				(width 0)
				(type default)
			)
			(fill yes)
			(layer "F.Fab")
		)
		(pad "1" smd rect
			(at -2.400046 -2.275078 270)
			(size 0.2286 0.6096)
			(layers "F.Cu" "F.Mask" "F.Paste")
			(net "PVDDCR_CPU0_P0_VOS1")
		)
		(pad "2" smd rect
			(at -2.400046 -1.82499 270)
			(size 0.2286 0.6096)
			(layers "F.Cu" "F.Mask" "F.Paste")
			(net "GND")
		)
		(pad "3" smd rect
			(at -2.400046 -1.374902 270)
			(size 0.2286 0.6096)
			(layers "F.Cu" "F.Mask" "F.Paste")
			(net "PVDDCR_CPU0_P0_VCC1")
		)
		(pad "4" smd rect
			(at -2.400046 -0.925068 270)
			(size 0.2286 0.6096)
			(layers "F.Cu" "F.Mask" "F.Paste")
			(net "PVDDCR_CPU0_P0_PVCC")
		)
		(pad "5" smd rect
			(at -2.400046 -0.47498 270)
			(size 0.2286 0.6096)
			(layers "F.Cu" "F.Mask" "F.Paste")
			(net "GND")
		)
		(pad "6" smd rect
			(at -2.400046 -0.024892 270)
			(size 0.2286 0.6096)
			(layers "F.Cu" "F.Mask" "F.Paste")
			(net "NC_PVDDCR_CPU0_P0_GL1_1")
		)
		(pad "7_9-20_24" smd circle
			(at 0 1.150112 270)
			(size 0 0)
			(layers "F.Cu" "F.Mask" "F.Paste")
			(net "GND")
		)
		(pad "10_19" smd rect
			(at 0 2.899918 270)
			(size 0.6096 4.318)
			(layers "F.Cu" "F.Mask" "F.Paste")
			(net "SW_PVDDCR_CPU0_P0_SW1")
		)
		(pad "25_29" smd rect
			(at 1.549908 -1.279906 90)
			(size 2.0574 2.3114)
			(layers "F.Cu" "F.Mask" "F.Paste")
			(net "SW_P12V_AUX_PVDDCR_CPU0_P0_FLT")
		)
		(pad "30" smd rect
			(at 2.05994 -2.899918 180)
			(size 0.2286 0.6096)
			(layers "F.Cu" "F.Mask" "F.Paste")
			(net "SW_P12V_AUX_PVDDCR_CPU0_P0_FLT")
		)
		(pad "31" smd rect
			(at 1.610106 -2.899918 180)
			(size 0.2286 0.6096)
			(layers "F.Cu" "F.Mask" "F.Paste")
			(net "NC_PVDDCR_CPU0_P0_DNC1")
		)
		(pad "32" smd rect
			(at 1.160018 -2.899918 180)
			(size 0.2286 0.6096)
			(layers "F.Cu" "F.Mask" "F.Paste")
			(net "SW_PVDDCR_CPU0_P0_PH1")
		)
		(pad "33" smd rect
			(at 0.70993 -2.899918 180)
			(size 0.2286 0.6096)
			(layers "F.Cu" "F.Mask" "F.Paste")
			(net "SW_PVDDCR_CPU0_P0_BOOT1")
		)
		(pad "34" smd rect
			(at 0.260096 -2.899918 180)
			(size 0.2286 0.6096)
			(layers "F.Cu" "F.Mask" "F.Paste")
			(net "PVDDCR_CPU0_P0_PWM1")
		)
		(pad "35" smd rect
			(at -0.189992 -2.899918 180)
			(size 0.2286 0.6096)
			(layers "F.Cu" "F.Mask" "F.Paste")
			(net "PVDDCR_CPU0_P0_VCC1")
		)
		(pad "36" smd rect
			(at -0.64008 -2.899918 180)
			(size 0.2286 0.6096)
			(layers "F.Cu" "F.Mask" "F.Paste")
			(net "PVDDCR_CPU0_P0_TEMP0")
		)
		(pad "37" smd rect
			(at -1.089914 -2.899918 180)
			(size 0.2286 0.6096)
			(layers "F.Cu" "F.Mask" "F.Paste")
			(net "PVDDCR_CPU0_P0_LSET1")
		)
		(pad "38" smd rect
			(at -1.540002 -2.899918 180)
			(size 0.2286 0.6096)
			(layers "F.Cu" "F.Mask" "F.Paste")
			(net "PVDDCR_CPU0_P0_IMON1")
		)
		(pad "39" smd rect
			(at -1.99009 -2.899918 180)
			(size 0.2286 0.6096)
			(layers "F.Cu" "F.Mask" "F.Paste")
			(net "PVDDCR_CPU0_P0_VCCS")
		)
		(pad "40" smd rect
			(at -0.87503 -1.27508 180)
			(size 1.7526 1.9558)
			(layers "F.Cu" "F.Mask" "F.Paste")
			(net "GND")
		)
		(pad "41" smd rect
			(at -1.525016 0.249936 90)
			(size 0.3048 0.4572)
			(layers "F.Cu" "F.Mask" "F.Paste")
			(net "NC_PVDDCR_CPU0_P0_GL2_1")
		)
		(zone
			(layer "F.Cu")
			(hatch none 0.5)
			(connect_pads
				(clearance 0)
			)
			(min_thickness 0.25)
			(keepout
				(tracks not_allowed)
				(vias allowed)
				(pads allowed)
				(copperpour not_allowed)
				(footprints allowed)
			)
			(placement
				(enabled no)
				(sheetname "")
			)
			(fill
				(thermal_gap 0.5)
				(thermal_bridge_width 0.5)
				(island_removal_mode 0)
			)
			(polygon
				(pts
					(xy 366.8141 -180.353462) (xy 366.8141 -180.021992) (xy 361.813856 -180.021992) (xy 361.813856 -180.350668)
					(xy 362.104178 -180.350668) (xy 362.104178 -180.315616) (xy 366.523778 -180.315616) (xy 366.523778 -180.353462)
				)
			)
		)
		(zone
			(layer "F.Cu")
			(hatch none 0.5)
			(connect_pads
				(clearance 0)
			)
			(min_thickness 0.25)
			(keepout
				(tracks not_allowed)
				(vias allowed)
				(pads allowed)
				(copperpour not_allowed)
				(footprints allowed)
			)
			(placement
				(enabled no)
				(sheetname "")
			)
			(fill
				(thermal_gap 0.5)
				(thermal_bridge_width 0.5)
				(island_removal_mode 0)
			)
			(polygon
				(pts
					(xy 364.261908 -177.52314) (xy 364.261908 -175.467518) (xy 366.116108 -175.467518) (xy 366.116108 -175.708564)
					(xy 366.358424 -175.708564) (xy 366.358424 -175.22698) (xy 362.445808 -175.22698) (xy 362.445808 -175.411892)
					(xy 363.97057 -175.411892) (xy 363.97057 -177.570892) (xy 361.813856 -177.570892) (xy 361.813856 -177.820574)
					(xy 363.964474 -177.820574)
				)
			)
		)
	)
	(footprint ""
		(layer "F.Cu")
		(at 65.1002 -18.6436 180)
		(property "Reference" "PC2152"
			(at 0 0 180)
			(layer "F.SilkS")
			(hide yes)
			(effects
				(font
					(size 1.27 1.27)
				)
			)
		)
		(property "Value" ""
			(at 0 0 180)
			(layer "F.Fab")
			(effects
				(font
					(size 1.27 1.27)
				)
			)
		)
		(duplicate_pad_numbers_are_jumpers no)
		(fp_line
			(start 0.7874 0.4064)
			(end -0.7874 0.4064)
			(stroke
				(width 0.1524)
				(type default)
			)
			(layer "F.SilkS")
		)
		(fp_line
			(start 0.7874 -0.4064)
			(end 0.7874 0.4064)
			(stroke
				(width 0.1524)
				(type default)
			)
			(layer "F.SilkS")
		)
		(fp_line
			(start -0.7874 0.4064)
			(end -0.7874 -0.4064)
			(stroke
				(width 0.1524)
				(type default)
			)
			(layer "F.SilkS")
		)
		(fp_line
			(start -0.7874 -0.4064)
			(end 0.7874 -0.4064)
			(stroke
				(width 0.1524)
				(type default)
			)
			(layer "F.SilkS")
		)
		(fp_line
			(start 0.67945 0.3048)
			(end 0.120396 0.3048)
			(stroke
				(width 0.1)
				(type default)
			)
			(layer "F.Fab")
		)
		(fp_line
			(start 0.67945 -0.3048)
			(end 0.67945 0.3048)
			(stroke
				(width 0.1)
				(type default)
			)
			(layer "F.Fab")
		)
		(fp_line
			(start 0.12065 -0.2794)
			(end 0.12065 -0.3048)
			(stroke
				(width 0.1)
				(type default)
			)
			(layer "F.Fab")
		)
		(fp_line
			(start 0.12065 -0.3048)
			(end 0.67945 -0.3048)
			(stroke
				(width 0.1)
				(type default)
			)
			(layer "F.Fab")
		)
		(fp_line
			(start 0.120396 0.3048)
			(end 0.120396 0.2794)
			(stroke
				(width 0.1)
				(type default)
			)
			(layer "F.Fab")
		)
		(fp_line
			(start 0.120396 0.2794)
			(end -0.12065 0.2794)
			(stroke
				(width 0.1)
				(type default)
			)
			(layer "F.Fab")
		)
		(fp_line
			(start -0.12065 0.3048)
			(end -0.67945 0.3048)
			(stroke
				(width 0.1)
				(type default)
			)
			(layer "F.Fab")
		)
		(fp_line
			(start -0.12065 0.2794)
			(end -0.12065 0.3048)
			(stroke
				(width 0.1)
				(type default)
			)
			(layer "F.Fab")
		)
		(fp_line
			(start -0.12065 -0.2794)
			(end 0.12065 -0.2794)
			(stroke
				(width 0.1)
				(type default)
			)
			(layer "F.Fab")
		)
		(fp_line
			(start -0.12065 -0.305054)
			(end -0.12065 -0.2794)
			(stroke
				(width 0.1)
				(type default)
			)
			(layer "F.Fab")
		)
		(fp_line
			(start -0.67945 0.3048)
			(end -0.67945 -0.305054)
			(stroke
				(width 0.1)
				(type default)
			)
			(layer "F.Fab")
		)
		(fp_line
			(start -0.67945 -0.305054)
			(end -0.12065 -0.305054)
			(stroke
				(width 0.1)
				(type default)
			)
			(layer "F.Fab")
		)
		(pad "1" smd circle
			(at -0.40005 0 180)
			(size 0 0)
			(layers "F.Cu" "F.Mask" "F.Paste")
			(net "P12V_OCP_V3_2")
		)
		(pad "2" smd circle
			(at 0.40005 0 180)
			(size 0 0)
			(layers "F.Cu" "F.Mask" "F.Paste")
			(net "GND")
		)
	)
	(footprint ""
		(layer "F.Cu")
		(at 439.295032 -25.330658 180)
		(property "Reference" "PC2158"
			(at 0 0 180)
			(layer "F.SilkS")
			(hide yes)
			(effects
				(font
					(size 1.27 1.27)
				)
			)
		)
		(property "Value" ""
			(at 0 0 180)
			(layer "F.Fab")
			(effects
				(font
					(size 1.27 1.27)
				)
			)
		)
		(duplicate_pad_numbers_are_jumpers no)
		(fp_line
			(start 1.2954 0.5842)
			(end -1.2954 0.5842)
			(stroke
				(width 0.1524)
				(type default)
			)
			(layer "F.SilkS")
		)
		(fp_line
			(start 1.2954 -0.5842)
			(end 1.2954 0.5842)
			(stroke
				(width 0.1524)
				(type default)
			)
			(layer "F.SilkS")
		)
		(fp_line
			(start -1.2954 0.5842)
			(end -1.2954 -0.5842)
			(stroke
				(width 0.1524)
				(type default)
			)
			(layer "F.SilkS")
		)
		(fp_line
			(start -1.2954 -0.5842)
			(end 1.2954 -0.5842)
			(stroke
				(width 0.1524)
				(type default)
			)
			(layer "F.SilkS")
		)
		(fp_line
			(start 1.1938 0.4064)
			(end 0.8636 0.4064)
			(stroke
				(width 0.1)
				(type default)
			)
			(layer "F.Fab")
		)
		(fp_line
			(start 1.1938 -0.4064)
			(end 1.1938 0.4064)
			(stroke
				(width 0.1)
				(type default)
			)
			(layer "F.Fab")
		)
		(fp_line
			(start 0.8636 0.4572)
			(end -0.8636 0.4572)
			(stroke
				(width 0.1)
				(type default)
			)
			(layer "F.Fab")
		)
		(fp_line
			(start 0.8636 0.4064)
			(end 0.8636 0.4572)
			(stroke
				(width 0.1)
				(type default)
			)
			(layer "F.Fab")
		)
		(fp_line
			(start 0.8636 -0.4064)
			(end 1.1938 -0.4064)
			(stroke
				(width 0.1)
				(type default)
			)
			(layer "F.Fab")
		)
		(fp_line
			(start 0.8636 -0.4572)
			(end 0.8636 -0.4064)
			(stroke
				(width 0.1)
				(type default)
			)
			(layer "F.Fab")
		)
		(fp_line
			(start -0.8636 0.4572)
			(end -0.8636 0.4064)
			(stroke
				(width 0.1)
				(type default)
			)
			(layer "F.Fab")
		)
		(fp_line
			(start -0.8636 0.4064)
			(end -1.1938 0.4064)
			(stroke
				(width 0.1)
				(type default)
			)
			(layer "F.Fab")
		)
		(fp_line
			(start -0.8636 -0.4064)
			(end -0.8636 -0.4572)
			(stroke
				(width 0.1)
				(type default)
			)
			(layer "F.Fab")
		)
		(fp_line
			(start -0.8636 -0.4572)
			(end 0.8636 -0.4572)
			(stroke
				(width 0.1)
				(type default)
			)
			(layer "F.Fab")
		)
		(fp_line
			(start -1.1938 0.4064)
			(end -1.1938 -0.4064)
			(stroke
				(width 0.1)
				(type default)
			)
			(layer "F.Fab")
		)
		(fp_line
			(start -1.1938 -0.4064)
			(end -0.8636 -0.4064)
			(stroke
				(width 0.1)
				(type default)
			)
			(layer "F.Fab")
		)
		(pad "1" smd rect
			(at -0.7366 0 90)
			(size 0.7112 0.8128)
			(layers "F.Cu" "F.Mask" "F.Paste")
			(net "P12V_OCP_AVIN_PD_1")
		)
		(pad "2" smd rect
			(at 0.7366 0 90)
			(size 0.7112 0.8128)
			(layers "F.Cu" "F.Mask" "F.Paste")
			(net "GND")
		)
	)
	(footprint ""
		(layer "F.Cu")
		(at 333.215488 -403.818852 -90)
		(property "Reference" "R1023"
			(at 0 0 270)
			(layer "F.SilkS")
			(hide yes)
			(effects
				(font
					(size 1.27 1.27)
				)
			)
		)
		(property "Value" ""
			(at 0 0 270)
			(layer "F.Fab")
			(effects
				(font
					(size 1.27 1.27)
				)
			)
		)
		(duplicate_pad_numbers_are_jumpers no)
		(fp_line
			(start -0.32512 0.175006)
			(end -0.32512 -0.175006)
			(stroke
				(width 0.1)
				(type default)
			)
			(layer "F.Fab")
		)
		(fp_line
			(start 0.32512 0.175006)
			(end -0.32512 0.175006)
			(stroke
				(width 0.1)
				(type default)
			)
			(layer "F.Fab")
		)
		(fp_line
			(start -0.32512 -0.175006)
			(end 0.32512 -0.175006)
			(stroke
				(width 0.1)
				(type default)
			)
			(layer "F.Fab")
		)
		(fp_line
			(start 0.32512 -0.175006)
			(end 0.32512 0.175006)
			(stroke
				(width 0.1)
				(type default)
			)
			(layer "F.Fab")
		)
		(pad "1" smd rect
			(at -0.2667 0 270)
			(size 0.3048 0.381)
			(layers "F.Cu" "F.Mask" "F.Paste")
			(net "P1V8_CPU0_RT_1D")
		)
		(pad "2" smd rect
			(at 0.2667 0 90)
			(size 0.3048 0.381)
			(layers "F.Cu" "F.Mask" "F.Paste")
			(net "RST_RT_CPU0_P1_RESET_R_N")
		)
	)
	(footprint ""
		(layer "F.Cu")
		(at 113.34496 -395.441932 -90)
		(property "Reference" "R925"
			(at 0 0 270)
			(layer "F.SilkS")
			(hide yes)
			(effects
				(font
					(size 1.27 1.27)
				)
			)
		)
		(property "Value" ""
			(at 0 0 270)
			(layer "F.Fab")
			(effects
				(font
					(size 1.27 1.27)
				)
			)
		)
		(duplicate_pad_numbers_are_jumpers no)
		(fp_line
			(start -0.32512 0.175006)
			(end -0.32512 -0.175006)
			(stroke
				(width 0.1)
				(type default)
			)
			(layer "F.Fab")
		)
		(fp_line
			(start 0.32512 0.175006)
			(end -0.32512 0.175006)
			(stroke
				(width 0.1)
				(type default)
			)
			(layer "F.Fab")
		)
		(fp_line
			(start -0.32512 -0.175006)
			(end 0.32512 -0.175006)
			(stroke
				(width 0.1)
				(type default)
			)
			(layer "F.Fab")
		)
		(fp_line
			(start 0.32512 -0.175006)
			(end 0.32512 0.175006)
			(stroke
				(width 0.1)
				(type default)
			)
			(layer "F.Fab")
		)
		(pad "1" smd rect
			(at -0.2667 0 270)
			(size 0.3048 0.381)
			(layers "F.Cu" "F.Mask" "F.Paste")
			(net "P1V8_CPU1_RT_1D")
		)
		(pad "2" smd rect
			(at 0.2667 0 90)
			(size 0.3048 0.381)
			(layers "F.Cu" "F.Mask" "F.Paste")
			(net "MODE_RT_CPU1_P3")
		)
	)
	(footprint ""
		(layer "F.Cu")
		(at 6.999986 -22.29993)
		(property "Reference" "H91"
			(at -5.190744 -5.784596 0)
			(unlocked yes)
			(layer "F.SilkS")
			(effects
				(font
					(size 0.7874 0.5842)
					(thickness 0.1524)
				)
				(justify left)
			)
		)
		(property "Value" ""
			(at 0 0 0)
			(layer "F.Fab")
			(effects
				(font
					(size 1.27 1.27)
				)
			)
		)
		(duplicate_pad_numbers_are_jumpers no)
		(pad "1" thru_hole circle
			(at 0 0)
			(size 10.0076 10.0076)
			(drill 5.6134)
			(layers "*.Cu" "*.Mask")
			(remove_unused_layers no)
			(net "GND")
			(clearance -1.9431)
		)
	)
)
